(kicad_pcb
	(version 20241229)
	(generator "pcbnew")
	(generator_version "9.0")
	(general
		(thickness 1.61)
		(legacy_teardrops no)
	)
	(paper "A3")
	(title_block
		(title "RDIMM DDR5 Tester")
		(date "2026-05-21")
		(rev "2.2.0")
		(company "Antmicro")
		(comment 9 "footprints 238-240 of 796")
	)
	(layers
		(0 "F.Cu" signal)
		(4 "In1.Cu" power)
		(6 "In2.Cu" mixed)
		(8 "In3.Cu" power)
		(10 "In4.Cu" mixed)
		(12 "In5.Cu" power)
		(14 "In6.Cu" mixed)
		(16 "In7.Cu" power)
		(18 "In8.Cu" power)
		(20 "In9.Cu" mixed)
		(22 "In10.Cu" power)
		(2 "B.Cu" signal)
		(9 "F.Adhes" user "F.Adhesive")
		(11 "B.Adhes" user "B.Adhesive")
		(13 "F.Paste" user)
		(15 "B.Paste" user)
		(5 "F.SilkS" user "F.Silkscreen")
		(7 "B.SilkS" user "B.Silkscreen")
		(1 "F.Mask" user)
		(3 "B.Mask" user)
		(17 "Dwgs.User" user "User.Drawings")
		(19 "Cmts.User" user "User.Comments")
		(21 "Eco1.User" user "User.Eco1")
		(23 "Eco2.User" user "User.Eco2")
		(25 "Edge.Cuts" user)
		(27 "Margin" user)
		(31 "F.CrtYd" user "F.Courtyard")
		(29 "B.CrtYd" user "B.Courtyard")
		(35 "F.Fab" user)
		(33 "B.Fab" user)
	)
	(footprint "antmicro-footprints:LED_0603_1608Metric_G"
		(layer "F.Cu")
		(at 137.424499 185.549 90)
		(descr "LED SMD 0603 Green")
		(tags "LED SMD 0603 Green")
		(property "Reference" "D11"
			(at -0.001 -0.901 90)
			(layer "F.SilkS")
			(hide yes)
			(effects
				(font
					(size 0.7 0.7)
					(thickness 0.15)
				)
				(justify left bottom)
			)
		)
		(property "Value" "LED_G_0603_KP-1608CGCK"
			(at -0.001 1.599 90)
			(layer "F.Fab")
			(effects
				(font
					(size 0.7 0.7)
					(thickness 0.15)
				)
				(justify left bottom)
			)
		)
		(property "Datasheet" "http://www.kingbright.com/attachments/file/psearch//000/00/00/KP-1608CGCK(Ver.23B).pdf"
			(at 0 0 90)
			(layer "F.Fab")
			(hide yes)
			(effects
				(font
					(size 1.27 1.27)
					(thickness 0.15)
				)
			)
		)
		(property "MPN" "KP-1608CGCK"
			(at 0 0 90)
			(unlocked yes)
			(layer "F.Fab")
			(hide yes)
			(effects
				(font
					(size 1 1)
					(thickness 0.15)
				)
			)
		)
		(property "Manufacturer" "Kingbright"
			(at 0 0 90)
			(unlocked yes)
			(layer "F.Fab")
			(hide yes)
			(effects
				(font
					(size 1 1)
					(thickness 0.15)
				)
			)
		)
		(property "Color" "Green"
			(at 0 0 90)
			(unlocked yes)
			(layer "F.Fab")
			(hide yes)
			(effects
				(font
					(size 1 1)
					(thickness 0.15)
				)
			)
		)
		(property "Author" "Antmicro"
			(at 0 0 90)
			(unlocked yes)
			(layer "F.Fab")
			(hide yes)
			(effects
				(font
					(size 1 1)
					(thickness 0.15)
				)
			)
		)
		(property "License" "Apache-2.0"
			(at 0 0 90)
			(unlocked yes)
			(layer "F.Fab")
			(hide yes)
			(effects
				(font
					(size 1 1)
					(thickness 0.15)
				)
			)
		)
		(sheetname "/Debug FTDI + VNA/")
		(sheetfile "debug-ftdi.kicad_sch")
		(attr smd)
		(fp_line
			(start 0.22 -0.35)
			(end -0.22 -0.35)
			(stroke
				(width 0.15)
				(type solid)
			)
			(layer "F.SilkS")
		)
		(fp_line
			(start -1.18 -0.319)
			(end -1.18 0.321)
			(stroke
				(width 0.15)
				(type solid)
			)
			(layer "F.SilkS")
		)
		(fp_line
			(start 0.105328 0.001008)
			(end 0.24 0.001)
			(stroke
				(width 0.1)
				(type solid)
			)
			(layer "F.SilkS")
		)
		(fp_line
			(start -0.094672 0.001008)
			(end 0.105328 -0.198992)
			(stroke
				(width 0.1)
				(type solid)
			)
			(layer "F.SilkS")
		)
		(fp_line
			(start -0.094672 0.001008)
			(end -0.24 0.001008)
			(stroke
				(width 0.1)
				(type solid)
			)
			(layer "F.SilkS")
		)
		(fp_line
			(start 0.105328 0.201008)
			(end 0.105328 -0.198992)
			(stroke
				(width 0.1)
				(type solid)
			)
			(layer "F.SilkS")
		)
		(fp_line
			(start 0.105328 0.201008)
			(end -0.094672 0.001008)
			(stroke
				(width 0.1)
				(type solid)
			)
			(layer "F.SilkS")
		)
		(fp_line
			(start -0.094672 0.201008)
			(end -0.094672 -0.198992)
			(stroke
				(width 0.1)
				(type solid)
			)
			(layer "F.SilkS")
		)
		(fp_line
			(start 0.22 0.35)
			(end -0.22 0.35)
			(stroke
				(width 0.15)
				(type solid)
			)
			(layer "F.SilkS")
		)
		(fp_rect
			(start 1.25 0.65)
			(end -1.25 -0.65)
			(stroke
				(width 0.05)
				(type solid)
			)
			(fill no)
			(layer "F.CrtYd")
		)
		(fp_line
			(start 0.201 -0.202)
			(end -0.101 0)
			(stroke
				(width 0.15)
				(type solid)
			)
			(layer "F.Fab")
		)
		(fp_line
			(start -0.199 -0.202)
			(end -0.199 0.1)
			(stroke
				(width 0.15)
				(type solid)
			)
			(layer "F.Fab")
		)
		(fp_line
			(start 0.599 0)
			(end 0.201 0)
			(stroke
				(width 0.15)
				(type solid)
			)
			(layer "F.Fab")
		)
		(fp_line
			(start 0.201 0)
			(end 0.201 -0.202)
			(stroke
				(width 0.15)
				(type solid)
			)
			(layer "F.Fab")
		)
		(fp_line
			(start -0.101 0)
			(end 0.201 0.2)
			(stroke
				(width 0.15)
				(type solid)
			)
			(layer "F.Fab")
		)
		(fp_line
			(start -0.199 0)
			(end -0.597 0)
			(stroke
				(width 0.15)
				(type solid)
			)
			(layer "F.Fab")
		)
		(fp_line
			(start 0.201 0.2)
			(end 0.201 0)
			(stroke
				(width 0.15)
				(type solid)
			)
			(layer "F.Fab")
		)
		(fp_line
			(start -0.199 0.2)
			(end -0.199 0.1)
			(stroke
				(width 0.15)
				(type solid)
			)
			(layer "F.Fab")
		)
		(fp_rect
			(start 0.848 0.4)
			(end -0.85 -0.402)
			(stroke
				(width 0.15)
				(type solid)
			)
			(fill no)
			(layer "F.Fab")
		)
		(fp_text user "Author: Antmicro"
			(at -1.4224 4.799 90)
			(layer "F.Fab")
			(effects
				(font
					(size 0.7 0.7)
					(thickness 0.15)
				)
				(justify left bottom)
			)
		)
		(fp_text user "License: Apache-2.0"
			(at -1.4224 3.599 90)
			(layer "F.Fab")
			(effects
				(font
					(size 0.7 0.7)
					(thickness 0.15)
				)
				(justify left bottom)
			)
		)
		(fp_text user "${REFERENCE}"
			(at -1.4224 5.999 90)
			(layer "F.Fab")
			(effects
				(font
					(size 0.7 0.7)
					(thickness 0.15)
				)
				(justify left bottom)
			)
		)
		(pad "1" smd roundrect
			(at -0.7 0 270)
			(size 0.8 1)
			(layers "F.Cu" "F.Mask" "F.Paste")
			(roundrect_rratio 0.2)
			(net 1 "GND")
			(pinfunction "C")
			(pintype "passive")
		)
		(pad "2" smd roundrect
			(at 0.7 0 270)
			(size 0.8 1)
			(layers "F.Cu" "F.Mask" "F.Paste")
			(roundrect_rratio 0.2)
			(net 41 "Net-(D11-A)")
			(pinfunction "A")
			(pintype "passive")
		)
	)
	(footprint "antmicro-footprints:TQFN-25_4x5mm"
		(layer "F.Cu")
		(at 229.945001 182.240001 -90)
		(property "Reference" "U36"
			(at 3.629999 4.315001 0)
			(unlocked yes)
			(layer "F.SilkS")
			(effects
				(font
					(size 0.7 0.7)
					(thickness 0.15)
				)
				(justify left bottom)
			)
		)
		(property "Value" "MP8796B"
			(at 12.501 7.605 270)
			(unlocked yes)
			(layer "F.Fab")
			(effects
				(font
					(size 0.7 0.7)
					(thickness 0.15)
				)
				(justify left bottom)
			)
		)
		(property "Datasheet" "https://www.monolithicpower.com/en/documentview/productdocument/index/version/2/document_type/Datasheet/lang/en/sku/MP8796B/"
			(at 0 0 270)
			(layer "F.Fab")
			(hide yes)
			(effects
				(font
					(size 1.27 1.27)
					(thickness 0.15)
				)
			)
		)
		(property "MPN" "MP8796BGVT-0000-Z"
			(at 0 0 270)
			(unlocked yes)
			(layer "F.Fab")
			(hide yes)
			(effects
				(font
					(size 1 1)
					(thickness 0.15)
				)
			)
		)
		(property "Manufacturer" "Monolithic Power Systems"
			(at 0 0 270)
			(unlocked yes)
			(layer "F.Fab")
			(hide yes)
			(effects
				(font
					(size 1 1)
					(thickness 0.15)
				)
			)
		)
		(property "Author" "Antmicro"
			(at 0 0 270)
			(unlocked yes)
			(layer "F.Fab")
			(hide yes)
			(effects
				(font
					(size 1 1)
					(thickness 0.15)
				)
			)
		)
		(property "License" "Apache-2.0"
			(at 0 0 270)
			(unlocked yes)
			(layer "F.Fab")
			(hide yes)
			(effects
				(font
					(size 1 1)
					(thickness 0.15)
				)
			)
		)
		(sheetname "/Supply/DC-DC VCCINT/")
		(sheetfile "dc-dc-vccint.kicad_sch")
		(attr smd)
		(fp_line
			(start -2.1 2.2)
			(end -2.1 1.7)
			(stroke
				(width 0.15)
				(type solid)
			)
			(layer "F.SilkS")
		)
		(fp_line
			(start 2.1 2.2)
			(end 2.1 1.7)
			(stroke
				(width 0.15)
				(type solid)
			)
			(layer "F.SilkS")
		)
		(fp_line
			(start -2.1 -1.7)
			(end -2.1 -2.2)
			(stroke
				(width 0.15)
				(type solid)
			)
			(layer "F.SilkS")
		)
		(fp_line
			(start 2.1 -2.2)
			(end 2.1 -1.7)
			(stroke
				(width 0.15)
				(type solid)
			)
			(layer "F.SilkS")
		)
		(fp_circle
			(center -2.34 -2.59)
			(end -2.29 -2.59)
			(stroke
				(width 0.15)
				(type solid)
			)
			(fill yes)
			(layer "F.SilkS")
		)
		(fp_rect
			(start -2.5 -2.75)
			(end 2.55 2.76)
			(stroke
				(width 0.05)
				(type solid)
			)
			(fill no)
			(layer "F.CrtYd")
		)
		(fp_text user "Author: Antmicro"
			(at -2.67 5.79 270)
			(layer "F.Fab")
			(effects
				(font
					(size 0.7 0.7)
					(thickness 0.15)
				)
				(justify left bottom)
			)
		)
		(fp_text user "License: Apache-2.0"
			(at -2.67 8.19 270)
			(layer "F.Fab")
			(effects
				(font
					(size 0.7 0.7)
					(thickness 0.15)
				)
				(justify left bottom)
			)
		)
		(fp_text user "${REFERENCE}"
			(at -2.67 6.99 270)
			(unlocked yes)
			(layer "F.Fab")
			(effects
				(font
					(size 0.7 0.7)
					(thickness 0.15)
				)
				(justify left bottom)
			)
		)
		(pad "1" smd roundrect
			(at -1.2 -1.195 90)
			(size 2.1 0.4)
			(layers "F.Cu" "F.Mask" "F.Paste")
			(roundrect_rratio 0.25)
			(net 35 "VDC")
			(pinfunction "IN")
			(pintype "power_in")
		)
		(pad "2" smd roundrect
			(at -1.2 -0.545 90)
			(size 2.1 0.4)
			(layers "F.Cu" "F.Mask" "F.Paste")
			(roundrect_rratio 0.25)
			(net 207 "Net-(C216-Pad2)")
			(pinfunction "SW")
			(pintype "passive")
		)
		(pad "3" smd roundrect
			(at -1.2 0.555 90)
			(size 2.1 0.4)
			(layers "F.Cu" "F.Mask" "F.Paste")
			(roundrect_rratio 0.25)
			(net 207 "Net-(C216-Pad2)")
			(pinfunction "SW")
			(pintype "passive")
		)
		(pad "4" smd roundrect
			(at -1.2 1.205 90)
			(size 2.1 0.4)
			(layers "F.Cu" "F.Mask" "F.Paste")
			(roundrect_rratio 0.25)
			(net 1 "GND")
			(pinfunction "P_{GND}")
			(pintype "passive")
		)
		(pad "5" smd roundrect
			(at -1.7 2.355)
			(size 0.9 0.3)
			(layers "F.Cu" "F.Mask" "F.Paste")
			(roundrect_rratio 0.25)
			(net 49 "Net-(U36-V_{DRV})")
			(pinfunction "V_{DRV}")
			(pintype "passive")
		)
		(pad "6" smd roundrect
			(at -1.2 2.355)
			(size 0.9 0.2)
			(layers "F.Cu" "F.Mask" "F.Paste")
			(roundrect_rratio 0.25)
			(net 749 "/I^{2}C + I3C/PWR.SCL")
			(pinfunction "SCL")
			(pintype "open_collector")
		)
		(pad "7" smd roundrect
			(at -0.8 2.355)
			(size 0.9 0.2)
			(layers "F.Cu" "F.Mask" "F.Paste")
			(roundrect_rratio 0.25)
			(net 533 "/I^{2}C + I3C/PWR.SDA")
			(pinfunction "SDA")
			(pintype "open_collector")
		)
		(pad "8" smd roundrect
			(at -0.4 2.355)
			(size 0.9 0.2)
			(layers "F.Cu" "F.Mask" "F.Paste")
			(roundrect_rratio 0.25)
			(net 748 "/Supply/DC-DC VCCINT/PWR.~{ALT}2")
			(pinfunction "~{ALT}")
			(pintype "open_collector")
		)
		(pad "9" smd roundrect
			(at 0 2.355)
			(size 0.9 0.2)
			(layers "F.Cu" "F.Mask" "F.Paste")
			(roundrect_rratio 0.25)
			(net 168 "/Supply/EN1")
			(pinfunction "CTRL")
			(pintype "input")
		)
		(pad "10" smd roundrect
			(at 0.4 2.355)
			(size 0.9 0.2)
			(layers "F.Cu" "F.Mask" "F.Paste")
			(roundrect_rratio 0.25)
			(net 482 "PG1")
			(pinfunction "PG")
			(pintype "open_collector")
		)
		(pad "11" smd roundrect
			(at 0.8 2.355)
			(size 0.9 0.2)
			(layers "F.Cu" "F.Mask" "F.Paste")
			(roundrect_rratio 0.25)
			(net 723 "/Supply/DC-DC VCCINT/PASS1")
			(pinfunction "PASS")
			(pintype "output")
		)
		(pad "12" smd roundrect
			(at 1.2 2.355)
			(size 0.9 0.2)
			(layers "F.Cu" "F.Mask" "F.Paste")
			(roundrect_rratio 0.25)
			(net 722 "/Supply/DC-DC VCCINT/TAKE1")
			(pinfunction "TAKE")
			(pintype "input")
		)
		(pad "13" smd roundrect
			(at 1.7 2.355)
			(size 0.9 0.3)
			(layers "F.Cu" "F.Mask" "F.Paste")
			(roundrect_rratio 0.25)
			(net 742 "/Supply/DC-DC VCCINT/SET")
			(pinfunction "SET")
			(pintype "bidirectional")
		)
		(pad "14" smd roundrect
			(at 1.2 1.205 90)
			(size 2.1 0.4)
			(layers "F.Cu" "F.Mask" "F.Paste")
			(roundrect_rratio 0.25)
			(net 1 "GND")
			(pinfunction "P_{GND}")
			(pintype "power_in")
		)
		(pad "15" smd roundrect
			(at 1.25 0.005 90)
			(size 2.1 0.4)
			(layers "F.Cu" "F.Mask" "F.Paste")
			(roundrect_rratio 0.25)
			(net 1 "GND")
			(pinfunction "P_{GND}")
			(pintype "passive")
		)
		(pad "16" smd roundrect
			(at 1.2 -1.195 90)
			(size 2.1 0.4)
			(layers "F.Cu" "F.Mask" "F.Paste")
			(roundrect_rratio 0.25)
			(net 35 "VDC")
			(pinfunction "IN")
			(pintype "passive")
		)
		(pad "17" smd roundrect
			(at 1.7 -2.345)
			(size 0.9 0.3)
			(layers "F.Cu" "F.Mask" "F.Paste")
			(roundrect_rratio 0.25)
			(net 777 "/Supply/DC-DC VCCINT/~{PS}")
			(pinfunction "~{PS}")
			(pintype "passive")
		)
		(pad "18" smd roundrect
			(at 1.2 -2.345)
			(size 0.9 0.2)
			(layers "F.Cu" "F.Mask" "F.Paste")
			(roundrect_rratio 0.25)
			(net 728 "Net-(U36-ADDR)")
			(pinfunction "ADDR")
			(pintype "passive")
		)
		(pad "19" smd roundrect
			(at 0.8 -2.345)
			(size 0.9 0.2)
			(layers "F.Cu" "F.Mask" "F.Paste")
			(roundrect_rratio 0.25)
			(net 743 "/Supply/DC-DC VCCINT/I_{SUM}")
			(pinfunction "I_{SUM}")
			(pintype "passive")
		)
		(pad "20" smd roundrect
			(at 0.4 -2.345)
			(size 0.9 0.2)
			(layers "F.Cu" "F.Mask" "F.Paste")
			(roundrect_rratio 0.25)
			(net 726 "Net-(U36-I_{REF})")
			(pinfunction "I_{REF}")
			(pintype "passive")
		)
		(pad "21" smd roundrect
			(at 0 -2.345)
			(size 0.9 0.2)
			(layers "F.Cu" "F.Mask" "F.Paste")
			(roundrect_rratio 0.25)
			(net 755 "/Supply/DC-DC VCCINT/VREF-")
			(pinfunction "V_{OSNS}-")
			(pintype "passive")
		)
		(pad "22" smd roundrect
			(at -0.4 -2.345)
			(size 0.9 0.2)
			(layers "F.Cu" "F.Mask" "F.Paste")
			(roundrect_rratio 0.25)
			(net 226 "/Supply/DC-DC VCCINT/V_{0SNS+}")
			(pinfunction "V_{OSNS}+")
			(pintype "passive")
		)
		(pad "23" smd roundrect
			(at -0.8 -2.345)
			(size 0.9 0.2)
			(layers "F.Cu" "F.Mask" "F.Paste")
			(roundrect_rratio 0.25)
			(net 1 "GND")
			(pinfunction "A_{GND}")
			(pintype "power_in")
		)
		(pad "24" smd roundrect
			(at -1.2 -2.345)
			(size 0.9 0.2)
			(layers "F.Cu" "F.Mask" "F.Paste")
			(roundrect_rratio 0.25)
			(net 163 "/Supply/DC-DC VCCINT/V_{CC}")
			(pinfunction "V_{CC}")
			(pintype "power_out")
		)
		(pad "25" smd roundrect
			(at -1.7 -2.345)
			(size 0.9 0.3)
			(layers "F.Cu" "F.Mask" "F.Paste")
			(roundrect_rratio 0.25)
			(net 167 "Net-(U36-BST)")
			(pinfunction "BST")
			(pintype "passive")
		)
	)
	(footprint "antmicro-footprints:C_0402_1005Metric"
		(layer "F.Cu")
		(at 113.026 171.5345 90)
		(descr "Capacitor SMD 0402")
		(tags "capacitor SMD 0402")
		(property "Reference" "C132"
			(at -2.6155 1.33 90)
			(layer "F.SilkS")
			(effects
				(font
					(size 0.7 0.7)
					(thickness 0.15)
				)
				(justify left bottom)
			)
		)
		(property "Value" "C_100n_0402"
			(at -1.022927 2.155213 90)
			(layer "F.Fab")
			(effects
				(font
					(size 0.7 0.7)
					(thickness 0.15)
				)
				(justify left bottom)
			)
		)
		(property "Datasheet" "https://www.murata.com/products/productdetail?partno=GRM155R61H104KE14%23"
			(at 0 0 90)
			(layer "F.Fab")
			(hide yes)
			(effects
				(font
					(size 1.27 1.27)
					(thickness 0.15)
				)
			)
		)
		(property "Manufacturer" "Murata"
			(at 0 0 90)
			(unlocked yes)
			(layer "F.Fab")
			(hide yes)
			(effects
				(font
					(size 1 1)
					(thickness 0.15)
				)
			)
		)
		(property "MPN" "GRM155R61H104KE14D"
			(at 0 0 90)
			(unlocked yes)
			(layer "F.Fab")
			(hide yes)
			(effects
				(font
					(size 1 1)
					(thickness 0.15)
				)
			)
		)
		(property "Val" "100n"
			(at 0 0 90)
			(unlocked yes)
			(layer "F.Fab")
			(hide yes)
			(effects
				(font
					(size 1 1)
					(thickness 0.15)
				)
			)
		)
		(property "License" "Apache-2.0"
			(at 0 0 90)
			(unlocked yes)
			(layer "F.Fab")
			(hide yes)
			(effects
				(font
					(size 1 1)
					(thickness 0.15)
				)
			)
		)
		(property "Author" "Antmicro"
			(at 0 0 90)
			(unlocked yes)
			(layer "F.Fab")
			(hide yes)
			(effects
				(font
					(size 1 1)
					(thickness 0.15)
				)
			)
		)
		(property "Voltage" "50V"
			(at 0 0 90)
			(unlocked yes)
			(layer "F.Fab")
			(hide yes)
			(effects
				(font
					(size 1 1)
					(thickness 0.15)
				)
			)
		)
		(property "Dielectric" "X5R"
			(at 0 0 90)
			(unlocked yes)
			(layer "F.Fab")
			(hide yes)
			(effects
				(font
					(size 1 1)
					(thickness 0.15)
				)
			)
		)
		(sheetname "/HDMI + SD Card/")
		(sheetfile "hdmi-sd-card.kicad_sch")
		(attr smd)
		(fp_rect
			(start -0.925 -0.47)
			(end 0.925 0.47)
			(stroke
				(width 0.05)
				(type default)
			)
			(fill no)
			(layer "F.CrtYd")
		)
		(fp_line
			(start 0.504 -0.25)
			(end 0.504 0.248)
			(stroke
				(width 0.15)
				(type solid)
			)
			(layer "F.Fab")
		)
		(fp_line
			(start -0.494 -0.25)
			(end 0.504 -0.25)
			(stroke
				(width 0.15)
				(type solid)
			)
			(layer "F.Fab")
		)
		(fp_line
			(start 0.504 0.248)
			(end -0.494 0.248)
			(stroke
				(width 0.15)
				(type solid)
			)
			(layer "F.Fab")
		)
		(fp_line
			(start -0.494 0.248)
			(end -0.494 -0.25)
			(stroke
				(width 0.15)
				(type solid)
			)
			(layer "F.Fab")
		)
		(fp_text user "License: Apache-2.0"
			(at -0.939 5.799 90)
			(layer "F.Fab")
			(effects
				(font
					(size 0.7 0.7)
					(thickness 0.15)
				)
				(justify left bottom)
			)
		)
		(fp_text user "${REFERENCE}"
			(at -0.939 4.599 90)
			(layer "F.Fab")
			(effects
				(font
					(size 0.7 0.7)
					(thickness 0.15)
				)
				(justify left bottom)
			)
		)
		(fp_text user "Author: Antmicro"
			(at -0.939 3.399 90)
			(layer "F.Fab")
			(effects
				(font
					(size 0.7 0.7)
					(thickness 0.15)
				)
				(justify left bottom)
			)
		)
		(pad "1" smd roundrect
			(at -0.48 0 90)
			(size 0.59 0.64)
			(layers "F.Cu" "F.Mask" "F.Paste")
			(roundrect_rratio 0.25)
			(net 188 "Net-(C132-Pad1)")
			(pintype "passive")
		)
		(pad "2" smd roundrect
			(at 0.48 0 90)
			(size 0.59 0.64)
			(layers "F.Cu" "F.Mask" "F.Paste")
			(roundrect_rratio 0.25)
			(net 1 "GND")
			(pintype "passive")
		)
	)
)
